(kicad_pcb
	(version 20260206)
	(generator "pcbnew")
	(generator_version "10.0")
	(general
		(thickness 1.6)
		(legacy_teardrops no)
	)
	(paper "A4")
	(title_block
		(title "03242023_DA0F0TMBIJ0_F0T_Motherboard_J_brd_V01_OCP.brd")
		(comment 1 "Grand Teton / footprint 501 of 6105 (J22), pads 113-224 of 291")
	)
	(layers
		(0 "F.Cu" signal "TOP")
		(4 "In1.Cu" signal "GND")
		(6 "In2.Cu" signal "IN1")
		(8 "In3.Cu" signal "GND1")
		(10 "In4.Cu" signal "IN2")
		(12 "In5.Cu" signal "GND2")
		(14 "In6.Cu" signal "IN3")
		(16 "In7.Cu" signal "GND3")
		(18 "In8.Cu" signal "VCC")
		(20 "In9.Cu" signal "VCC1")
		(22 "In10.Cu" signal "GND4")
		(24 "In11.Cu" signal "IN4")
		(26 "In12.Cu" signal "GND5")
		(28 "In13.Cu" signal "IN5")
		(30 "In14.Cu" signal "GND6")
		(32 "In15.Cu" signal "IN6")
		(34 "In16.Cu" signal "GND7")
		(2 "B.Cu" signal "BOTTOM")
		(9 "F.Adhes" user "F.Adhesive")
		(11 "B.Adhes" user "B.Adhesive")
		(13 "F.Paste" user "Package Geometry/Pastemask Top")
		(15 "B.Paste" user "Package Geometry/Pastemask Bottom")
		(5 "F.SilkS" user "Ref Des/Silkscreen Top")
		(7 "B.SilkS" user "Ref Des/Silkscreen Bottom")
		(1 "F.Mask" user "Board Geometry/Soldermask Top")
		(3 "B.Mask" user "Board Geometry/Soldermask Bottom")
		(17 "Dwgs.User" user "User.Drawings")
		(19 "Cmts.User" user "User.Comments")
		(21 "Eco1.User" user "User.Eco1")
		(23 "Eco2.User" user "User.Eco2")
		(25 "Edge.Cuts" user "Board Geometry/Outline")
		(27 "Margin" user)
		(31 "F.CrtYd" user "Package Geometry/Place Bound Top")
		(29 "B.CrtYd" user "Package Geometry/Place Bound Bottom")
		(35 "F.Fab" user "Ref Des/Assembly Top")
		(33 "B.Fab" user "Ref Des/Assembly Bottom")
	)
	(footprint ""
		(layer "F.Cu")
		(at 32.82188 -258.091686)
		(property "Reference" "J22"
			(at -1.420622 -81.912714 0)
			(unlocked yes)
			(layer "F.SilkS")
			(effects
				(font
					(size 0.7874 0.5842)
					(thickness 0.1524)
				)
				(justify left)
			)
		)
		(property "Value" ""
			(at 0 0 0)
			(layer "F.Fab")
			(effects
				(font
					(size 1.27 1.27)
				)
			)
		)
		(duplicate_pad_numbers_are_jumpers no)
		(pad "113" smd rect
			(at -2.050034 36.975034 270)
			(size 0.519938 1.4986)
			(layers "F.Cu" "F.Mask" "F.Paste")
			(net "M_C_CPU1_SB_DQ<9>")
		)
		(pad "114" smd rect
			(at -2.050034 37.824918 270)
			(size 0.519938 1.4986)
			(layers "F.Cu" "F.Mask" "F.Paste")
			(net "GND")
		)
		(pad "115" smd rect
			(at -2.050034 38.675056 270)
			(size 0.519938 1.4986)
			(layers "F.Cu" "F.Mask" "F.Paste")
			(net "M_C_CPU1_SB_DQS_DP<1>")
		)
		(pad "116" smd rect
			(at -2.050034 39.52494 270)
			(size 0.519938 1.4986)
			(layers "F.Cu" "F.Mask" "F.Paste")
			(net "M_C_CPU1_SB_DQS_DN<1>")
		)
		(pad "117" smd rect
			(at -2.050034 40.375078 270)
			(size 0.519938 1.4986)
			(layers "F.Cu" "F.Mask" "F.Paste")
			(net "GND")
		)
		(pad "118" smd rect
			(at -2.050034 41.224962 270)
			(size 0.519938 1.4986)
			(layers "F.Cu" "F.Mask" "F.Paste")
			(net "M_C_CPU1_SB_DQ<12>")
		)
		(pad "119" smd rect
			(at -2.050034 42.0751 270)
			(size 0.519938 1.4986)
			(layers "F.Cu" "F.Mask" "F.Paste")
			(net "GND")
		)
		(pad "120" smd rect
			(at -2.050034 42.924984 270)
			(size 0.519938 1.4986)
			(layers "F.Cu" "F.Mask" "F.Paste")
			(net "M_C_CPU1_SB_DQ<13>")
		)
		(pad "121" smd rect
			(at -2.050034 43.775122 270)
			(size 0.519938 1.4986)
			(layers "F.Cu" "F.Mask" "F.Paste")
			(net "GND")
		)
		(pad "122" smd rect
			(at -2.050034 44.625006 270)
			(size 0.519938 1.4986)
			(layers "F.Cu" "F.Mask" "F.Paste")
			(net "M_C_CPU1_SB_DQ<16>")
		)
		(pad "123" smd rect
			(at -2.050034 45.47489 270)
			(size 0.519938 1.4986)
			(layers "F.Cu" "F.Mask" "F.Paste")
			(net "GND")
		)
		(pad "124" smd rect
			(at -2.050034 46.325028 270)
			(size 0.519938 1.4986)
			(layers "F.Cu" "F.Mask" "F.Paste")
			(net "M_C_CPU1_SB_DQ<17>")
		)
		(pad "125" smd rect
			(at -2.050034 47.174912 270)
			(size 0.519938 1.4986)
			(layers "F.Cu" "F.Mask" "F.Paste")
			(net "GND")
		)
		(pad "126" smd rect
			(at -2.050034 48.02505 270)
			(size 0.519938 1.4986)
			(layers "F.Cu" "F.Mask" "F.Paste")
			(net "M_C_CPU1_SB_DQS_DP<2>")
		)
		(pad "127" smd rect
			(at -2.050034 48.874934 270)
			(size 0.519938 1.4986)
			(layers "F.Cu" "F.Mask" "F.Paste")
			(net "M_C_CPU1_SB_DQS_DN<2>")
		)
		(pad "128" smd rect
			(at -2.050034 49.725072 270)
			(size 0.519938 1.4986)
			(layers "F.Cu" "F.Mask" "F.Paste")
			(net "GND")
		)
		(pad "129" smd rect
			(at -2.050034 50.574956 270)
			(size 0.519938 1.4986)
			(layers "F.Cu" "F.Mask" "F.Paste")
			(net "M_C_CPU1_SB_DQ<20>")
		)
		(pad "130" smd rect
			(at -2.050034 51.425094 270)
			(size 0.519938 1.4986)
			(layers "F.Cu" "F.Mask" "F.Paste")
			(net "GND")
		)
		(pad "131" smd rect
			(at -2.050034 52.274978 270)
			(size 0.519938 1.4986)
			(layers "F.Cu" "F.Mask" "F.Paste")
			(net "M_C_CPU1_SB_DQ<21>")
		)
		(pad "132" smd rect
			(at -2.050034 53.125116 270)
			(size 0.519938 1.4986)
			(layers "F.Cu" "F.Mask" "F.Paste")
			(net "GND")
		)
		(pad "133" smd rect
			(at -2.050034 53.975 270)
			(size 0.519938 1.4986)
			(layers "F.Cu" "F.Mask" "F.Paste")
			(net "M_C_CPU1_SB_DQ<24>")
		)
		(pad "134" smd rect
			(at -2.050034 54.824884 270)
			(size 0.519938 1.4986)
			(layers "F.Cu" "F.Mask" "F.Paste")
			(net "GND")
		)
		(pad "135" smd rect
			(at -2.050034 55.675022 270)
			(size 0.519938 1.4986)
			(layers "F.Cu" "F.Mask" "F.Paste")
			(net "M_C_CPU1_SB_DQ<25>")
		)
		(pad "136" smd rect
			(at -2.050034 56.524906 270)
			(size 0.519938 1.4986)
			(layers "F.Cu" "F.Mask" "F.Paste")
			(net "GND")
		)
		(pad "137" smd rect
			(at -2.050034 57.375044 270)
			(size 0.519938 1.4986)
			(layers "F.Cu" "F.Mask" "F.Paste")
			(net "M_C_CPU1_SB_DQS_DP<3>")
		)
		(pad "138" smd rect
			(at -2.050034 58.224928 270)
			(size 0.519938 1.4986)
			(layers "F.Cu" "F.Mask" "F.Paste")
			(net "M_C_CPU1_SB_DQS_DN<3>")
		)
		(pad "139" smd rect
			(at -2.050034 59.075066 270)
			(size 0.519938 1.4986)
			(layers "F.Cu" "F.Mask" "F.Paste")
			(net "GND")
		)
		(pad "140" smd rect
			(at -2.050034 59.92495 270)
			(size 0.519938 1.4986)
			(layers "F.Cu" "F.Mask" "F.Paste")
			(net "M_C_CPU1_SB_DQ<28>")
		)
		(pad "141" smd rect
			(at -2.050034 60.775088 270)
			(size 0.519938 1.4986)
			(layers "F.Cu" "F.Mask" "F.Paste")
			(net "GND")
		)
		(pad "142" smd rect
			(at -2.050034 61.624972 270)
			(size 0.519938 1.4986)
			(layers "F.Cu" "F.Mask" "F.Paste")
			(net "M_C_CPU1_SB_DQ<29>")
		)
		(pad "143" smd rect
			(at -2.050034 62.47511 270)
			(size 0.519938 1.4986)
			(layers "F.Cu" "F.Mask" "F.Paste")
			(net "GND")
		)
		(pad "144" smd rect
			(at -2.050034 63.324994 270)
			(size 0.519938 1.4986)
			(layers "F.Cu" "F.Mask" "F.Paste")
			(net "TP_CHC_CPU1_DIMM2_FRU_1")
		)
		(pad "145" smd rect
			(at 2.050034 -63.324994 270)
			(size 0.519938 1.4986)
			(layers "F.Cu" "F.Mask" "F.Paste")
			(net "P12V_S3_AUX_CPU1_NVDIMM")
		)
		(pad "146" smd rect
			(at 2.050034 -62.47511 270)
			(size 0.519938 1.4986)
			(layers "F.Cu" "F.Mask" "F.Paste")
			(net "P12V_S3_AUX_CPU1_NVDIMM")
		)
		(pad "147" smd rect
			(at 2.050034 -61.624972 270)
			(size 0.519938 1.4986)
			(layers "F.Cu" "F.Mask" "F.Paste")
			(net "PWRGD_CHC_CPU1_DIMM2")
		)
		(pad "148" smd rect
			(at 2.050034 -60.775088 270)
			(size 0.519938 1.4986)
			(layers "F.Cu" "F.Mask" "F.Paste")
			(net "PD_CHC_CPU1_DIMM2_SAA")
		)
		(pad "149" smd rect
			(at 2.050034 -59.92495 270)
			(size 0.519938 1.4986)
			(layers "F.Cu" "F.Mask" "F.Paste")
			(net "TP_CHC_CPU1_DIMM2_FRU_2")
		)
		(pad "150" smd rect
			(at 2.050034 -59.075066 270)
			(size 0.519938 1.4986)
			(layers "F.Cu" "F.Mask" "F.Paste")
			(net "TP_CHC_CPU1_DIMM2_FRU_3")
		)
		(pad "151" smd rect
			(at 2.050034 -58.224928 270)
			(size 0.519938 1.4986)
			(layers "F.Cu" "F.Mask" "F.Paste")
			(net "GND")
		)
		(pad "152" smd rect
			(at 2.050034 -57.375044 270)
			(size 0.519938 1.4986)
			(layers "F.Cu" "F.Mask" "F.Paste")
			(net "M_C_CPU1_SA_DQ<2>")
		)
		(pad "153" smd rect
			(at 2.050034 -56.524906 270)
			(size 0.519938 1.4986)
			(layers "F.Cu" "F.Mask" "F.Paste")
			(net "GND")
		)
		(pad "154" smd rect
			(at 2.050034 -55.675022 270)
			(size 0.519938 1.4986)
			(layers "F.Cu" "F.Mask" "F.Paste")
			(net "M_C_CPU1_SA_DQ<3>")
		)
		(pad "155" smd rect
			(at 2.050034 -54.824884 270)
			(size 0.519938 1.4986)
			(layers "F.Cu" "F.Mask" "F.Paste")
			(net "GND")
		)
		(pad "156" smd rect
			(at 2.050034 -53.975 270)
			(size 0.519938 1.4986)
			(layers "F.Cu" "F.Mask" "F.Paste")
			(net "M_C_CPU1_SA_DQS_DN<5>")
		)
		(pad "157" smd rect
			(at 2.050034 -53.125116 270)
			(size 0.519938 1.4986)
			(layers "F.Cu" "F.Mask" "F.Paste")
			(net "M_C_CPU1_SA_DQS_DP<5>")
		)
		(pad "158" smd rect
			(at 2.050034 -52.274978 270)
			(size 0.519938 1.4986)
			(layers "F.Cu" "F.Mask" "F.Paste")
			(net "GND")
		)
		(pad "159" smd rect
			(at 2.050034 -51.425094 270)
			(size 0.519938 1.4986)
			(layers "F.Cu" "F.Mask" "F.Paste")
			(net "M_C_CPU1_SA_DQ<6>")
		)
		(pad "160" smd rect
			(at 2.050034 -50.574956 270)
			(size 0.519938 1.4986)
			(layers "F.Cu" "F.Mask" "F.Paste")
			(net "GND")
		)
		(pad "161" smd rect
			(at 2.050034 -49.725072 270)
			(size 0.519938 1.4986)
			(layers "F.Cu" "F.Mask" "F.Paste")
			(net "M_C_CPU1_SA_DQ<7>")
		)
		(pad "162" smd rect
			(at 2.050034 -48.874934 270)
			(size 0.519938 1.4986)
			(layers "F.Cu" "F.Mask" "F.Paste")
			(net "GND")
		)
		(pad "163" smd rect
			(at 2.050034 -48.02505 270)
			(size 0.519938 1.4986)
			(layers "F.Cu" "F.Mask" "F.Paste")
			(net "M_C_CPU1_SA_DQ<10>")
		)
		(pad "164" smd rect
			(at 2.050034 -47.174912 270)
			(size 0.519938 1.4986)
			(layers "F.Cu" "F.Mask" "F.Paste")
			(net "GND")
		)
		(pad "165" smd rect
			(at 2.050034 -46.325028 270)
			(size 0.519938 1.4986)
			(layers "F.Cu" "F.Mask" "F.Paste")
			(net "M_C_CPU1_SA_DQ<11>")
		)
		(pad "166" smd rect
			(at 2.050034 -45.47489 270)
			(size 0.519938 1.4986)
			(layers "F.Cu" "F.Mask" "F.Paste")
			(net "GND")
		)
		(pad "167" smd rect
			(at 2.050034 -44.625006 270)
			(size 0.519938 1.4986)
			(layers "F.Cu" "F.Mask" "F.Paste")
			(net "M_C_CPU1_SA_DQS_DN<6>")
		)
		(pad "168" smd rect
			(at 2.050034 -43.775122 270)
			(size 0.519938 1.4986)
			(layers "F.Cu" "F.Mask" "F.Paste")
			(net "M_C_CPU1_SA_DQS_DP<6>")
		)
		(pad "169" smd rect
			(at 2.050034 -42.924984 270)
			(size 0.519938 1.4986)
			(layers "F.Cu" "F.Mask" "F.Paste")
			(net "GND")
		)
		(pad "170" smd rect
			(at 2.050034 -42.0751 270)
			(size 0.519938 1.4986)
			(layers "F.Cu" "F.Mask" "F.Paste")
			(net "M_C_CPU1_SA_DQ<14>")
		)
		(pad "171" smd rect
			(at 2.050034 -41.224962 270)
			(size 0.519938 1.4986)
			(layers "F.Cu" "F.Mask" "F.Paste")
			(net "GND")
		)
		(pad "172" smd rect
			(at 2.050034 -40.375078 270)
			(size 0.519938 1.4986)
			(layers "F.Cu" "F.Mask" "F.Paste")
			(net "M_C_CPU1_SA_DQ<15>")
		)
		(pad "173" smd rect
			(at 2.050034 -39.52494 270)
			(size 0.519938 1.4986)
			(layers "F.Cu" "F.Mask" "F.Paste")
			(net "GND")
		)
		(pad "174" smd rect
			(at 2.050034 -38.675056 270)
			(size 0.519938 1.4986)
			(layers "F.Cu" "F.Mask" "F.Paste")
			(net "M_C_CPU1_SA_DQ<18>")
		)
		(pad "175" smd rect
			(at 2.050034 -37.824918 270)
			(size 0.519938 1.4986)
			(layers "F.Cu" "F.Mask" "F.Paste")
			(net "GND")
		)
		(pad "176" smd rect
			(at 2.050034 -36.975034 270)
			(size 0.519938 1.4986)
			(layers "F.Cu" "F.Mask" "F.Paste")
			(net "M_C_CPU1_SA_DQ<19>")
		)
		(pad "177" smd rect
			(at 2.050034 -36.124896 270)
			(size 0.519938 1.4986)
			(layers "F.Cu" "F.Mask" "F.Paste")
			(net "GND")
		)
		(pad "178" smd rect
			(at 2.050034 -35.275012 270)
			(size 0.519938 1.4986)
			(layers "F.Cu" "F.Mask" "F.Paste")
			(net "M_C_CPU1_SA_DQS_DN<7>")
		)
		(pad "179" smd rect
			(at 2.050034 -34.425128 270)
			(size 0.519938 1.4986)
			(layers "F.Cu" "F.Mask" "F.Paste")
			(net "M_C_CPU1_SA_DQS_DP<7>")
		)
		(pad "180" smd rect
			(at 2.050034 -33.57499 270)
			(size 0.519938 1.4986)
			(layers "F.Cu" "F.Mask" "F.Paste")
			(net "GND")
		)
		(pad "181" smd rect
			(at 2.050034 -32.725106 270)
			(size 0.519938 1.4986)
			(layers "F.Cu" "F.Mask" "F.Paste")
			(net "M_C_CPU1_SA_DQ<22>")
		)
		(pad "182" smd rect
			(at 2.050034 -31.874968 270)
			(size 0.519938 1.4986)
			(layers "F.Cu" "F.Mask" "F.Paste")
			(net "GND")
		)
		(pad "183" smd rect
			(at 2.050034 -31.025084 270)
			(size 0.519938 1.4986)
			(layers "F.Cu" "F.Mask" "F.Paste")
			(net "M_C_CPU1_SA_DQ<23>")
		)
		(pad "184" smd rect
			(at 2.050034 -30.174946 270)
			(size 0.519938 1.4986)
			(layers "F.Cu" "F.Mask" "F.Paste")
			(net "GND")
		)
		(pad "185" smd rect
			(at 2.050034 -29.325062 270)
			(size 0.519938 1.4986)
			(layers "F.Cu" "F.Mask" "F.Paste")
			(net "M_C_CPU1_SA_DQ<26>")
		)
		(pad "186" smd rect
			(at 2.050034 -28.474924 270)
			(size 0.519938 1.4986)
			(layers "F.Cu" "F.Mask" "F.Paste")
			(net "GND")
		)
		(pad "187" smd rect
			(at 2.050034 -27.62504 270)
			(size 0.519938 1.4986)
			(layers "F.Cu" "F.Mask" "F.Paste")
			(net "M_C_CPU1_SA_DQ<27>")
		)
		(pad "188" smd rect
			(at 2.050034 -26.774902 270)
			(size 0.519938 1.4986)
			(layers "F.Cu" "F.Mask" "F.Paste")
			(net "GND")
		)
		(pad "189" smd rect
			(at 2.050034 -25.925018 270)
			(size 0.519938 1.4986)
			(layers "F.Cu" "F.Mask" "F.Paste")
			(net "M_C_CPU1_SA_DQS_DN<8>")
		)
		(pad "190" smd rect
			(at 2.050034 -25.07488 270)
			(size 0.519938 1.4986)
			(layers "F.Cu" "F.Mask" "F.Paste")
			(net "M_C_CPU1_SA_DQS_DP<8>")
		)
		(pad "191" smd rect
			(at 2.050034 -24.224996 270)
			(size 0.519938 1.4986)
			(layers "F.Cu" "F.Mask" "F.Paste")
			(net "GND")
		)
		(pad "192" smd rect
			(at 2.050034 -23.375112 270)
			(size 0.519938 1.4986)
			(layers "F.Cu" "F.Mask" "F.Paste")
			(net "M_C_CPU1_SA_DQ<30>")
		)
		(pad "193" smd rect
			(at 2.050034 -22.524974 270)
			(size 0.519938 1.4986)
			(layers "F.Cu" "F.Mask" "F.Paste")
			(net "GND")
		)
		(pad "194" smd rect
			(at 2.050034 -21.67509 270)
			(size 0.519938 1.4986)
			(layers "F.Cu" "F.Mask" "F.Paste")
			(net "M_C_CPU1_SA_DQ<31>")
		)
		(pad "195" smd rect
			(at 2.050034 -20.824952 270)
			(size 0.519938 1.4986)
			(layers "F.Cu" "F.Mask" "F.Paste")
			(net "GND")
		)
		(pad "196" smd rect
			(at 2.050034 -19.975068 270)
			(size 0.519938 1.4986)
			(layers "F.Cu" "F.Mask" "F.Paste")
			(net "M_C_CPU1_SA_CB<2>")
		)
		(pad "197" smd rect
			(at 2.050034 -19.12493 270)
			(size 0.519938 1.4986)
			(layers "F.Cu" "F.Mask" "F.Paste")
			(net "GND")
		)
		(pad "198" smd rect
			(at 2.050034 -18.275046 270)
			(size 0.519938 1.4986)
			(layers "F.Cu" "F.Mask" "F.Paste")
			(net "M_C_CPU1_SA_CB<3>")
		)
		(pad "199" smd rect
			(at 2.050034 -17.424908 270)
			(size 0.519938 1.4986)
			(layers "F.Cu" "F.Mask" "F.Paste")
			(net "GND")
		)
		(pad "200" smd rect
			(at 2.050034 -16.575024 270)
			(size 0.519938 1.4986)
			(layers "F.Cu" "F.Mask" "F.Paste")
			(net "M_C_CPU1_SA_DQS_DN<9>")
		)
		(pad "201" smd rect
			(at 2.050034 -15.724886 270)
			(size 0.519938 1.4986)
			(layers "F.Cu" "F.Mask" "F.Paste")
			(net "M_C_CPU1_SA_DQS_DP<9>")
		)
		(pad "202" smd rect
			(at 2.050034 -14.875002 270)
			(size 0.519938 1.4986)
			(layers "F.Cu" "F.Mask" "F.Paste")
			(net "GND")
		)
		(pad "203" smd rect
			(at 2.050034 -14.025118 270)
			(size 0.519938 1.4986)
			(layers "F.Cu" "F.Mask" "F.Paste")
			(net "M_C_CPU1_SA_CB<6>")
		)
		(pad "204" smd rect
			(at 2.050034 -13.17498 270)
			(size 0.519938 1.4986)
			(layers "F.Cu" "F.Mask" "F.Paste")
			(net "GND")
		)
		(pad "205" smd rect
			(at 2.050034 -12.325096 270)
			(size 0.519938 1.4986)
			(layers "F.Cu" "F.Mask" "F.Paste")
			(net "M_C_CPU1_SA_CB<7>")
		)
		(pad "206" smd rect
			(at 2.050034 -11.474958 270)
			(size 0.519938 1.4986)
			(layers "F.Cu" "F.Mask" "F.Paste")
			(net "GND")
		)
		(pad "207" smd rect
			(at 2.050034 -10.625074 270)
			(size 0.519938 1.4986)
			(layers "F.Cu" "F.Mask" "F.Paste")
			(net "RST_M_CD_CPU1_FPGA_N")
		)
		(pad "208" smd rect
			(at 2.050034 -9.774936 270)
			(size 0.519938 1.4986)
			(layers "F.Cu" "F.Mask" "F.Paste")
			(net "GND")
		)
		(pad "209" smd rect
			(at 2.050034 -8.925052 270)
			(size 0.519938 1.4986)
			(layers "F.Cu" "F.Mask" "F.Paste")
			(net "M_C_CPU1_SA_CS_N<3>")
		)
		(pad "210" smd rect
			(at 2.050034 -8.074914 270)
			(size 0.519938 1.4986)
			(layers "F.Cu" "F.Mask" "F.Paste")
			(net "GND")
		)
		(pad "211" smd rect
			(at 2.050034 -7.22503 270)
			(size 0.519938 1.4986)
			(layers "F.Cu" "F.Mask" "F.Paste")
			(net "M_C_CPU1_SA_CA<1>")
		)
		(pad "212" smd rect
			(at 2.050034 -6.374892 270)
			(size 0.519938 1.4986)
			(layers "F.Cu" "F.Mask" "F.Paste")
			(net "GND")
		)
		(pad "213" smd rect
			(at 2.050034 -5.525008 270)
			(size 0.519938 1.4986)
			(layers "F.Cu" "F.Mask" "F.Paste")
			(net "M_C_CPU1_SA_CA<3>")
		)
		(pad "214" smd rect
			(at 2.050034 -4.675124 270)
			(size 0.519938 1.4986)
			(layers "F.Cu" "F.Mask" "F.Paste")
			(net "GND")
		)
		(pad "215" smd rect
			(at 2.050034 -3.824986 270)
			(size 0.519938 1.4986)
			(layers "F.Cu" "F.Mask" "F.Paste")
			(net "M_C_CPU1_SA_CA<5>")
		)
		(pad "216" smd rect
			(at 2.050034 -2.975102 270)
			(size 0.519938 1.4986)
			(layers "F.Cu" "F.Mask" "F.Paste")
			(net "GND")
		)
		(pad "217" smd rect
			(at 2.050034 -2.124964 270)
			(size 0.519938 1.4986)
			(layers "F.Cu" "F.Mask" "F.Paste")
			(net "M_C_CPU1_CLK_DP<1>")
		)
		(pad "218" smd rect
			(at 2.050034 -1.27508 270)
			(size 0.519938 1.4986)
			(layers "F.Cu" "F.Mask" "F.Paste")
			(net "M_C_CPU1_CLK_DN<1>")
		)
		(pad "219" smd rect
			(at 2.050034 -0.424942 270)
			(size 0.519938 1.4986)
			(layers "F.Cu" "F.Mask" "F.Paste")
			(net "GND")
		)
		(pad "220" smd rect
			(at 2.050034 5.525008 270)
			(size 0.519938 1.4986)
			(layers "F.Cu" "F.Mask" "F.Paste")
			(net "TP_CHC_CPU1_DIMM2_FRU_4")
		)
		(pad "221" smd rect
			(at 2.050034 6.374892 270)
			(size 0.519938 1.4986)
			(layers "F.Cu" "F.Mask" "F.Paste")
			(net "M_C_CPU1_SB_CA<1>")
		)
		(pad "222" smd rect
			(at 2.050034 7.22503 270)
			(size 0.519938 1.4986)
			(layers "F.Cu" "F.Mask" "F.Paste")
			(net "GND")
		)
		(pad "223" smd rect
			(at 2.050034 8.074914 270)
			(size 0.519938 1.4986)
			(layers "F.Cu" "F.Mask" "F.Paste")
			(net "M_C_CPU1_SB_CA<3>")
		)
		(pad "224" smd rect
			(at 2.050034 8.925052 270)
			(size 0.519938 1.4986)
			(layers "F.Cu" "F.Mask" "F.Paste")
			(net "GND")
		)
	)
)
